# TIMECARD (Time Appliance Project (Time Card)) — schematic netlist excerpt (pin names and nets, part order shuffled) for the footprints in the layout excerpt that follows; sources: Cadence DE-HDL packaged netlist, KiCad conversion of R4006-B0001-02_R01.brd

R284  RESISTOR  4.7KOHM 1%  pkg SMC_0402R_H016  page 25 : \1\ = SG ; \2\ = FPGA_IO_2
C100  CAPACITOR  0.1UF 25V 10%  pkg SMC_0402R_H022  page 24 : \1\ = XP3R3V_VPLL ; \2\ = SG

(kicad_pcb
	(version 20260206)
	(generator "pcbnew")
	(generator_version "10.0")
	(general
		(thickness 1.6)
		(legacy_teardrops no)
	)
	(paper "A4")
	(title_block
		(title "timecard-production-celestica-r4006 — R4006-B0001-02_R01.brd")
		(comment 1 "Time Appliance Project (Time Card) / footprints 698-699 of 1113")
	)
	(layers
		(0 "F.Cu" signal "TOP")
		(4 "In1.Cu" signal "L02_GND1")
		(6 "In2.Cu" signal "L03_SIG1")
		(8 "In3.Cu" signal "L04_GND2")
		(10 "In4.Cu" signal "L05_VCC1")
		(12 "In5.Cu" signal "L06_VCC2")
		(14 "In6.Cu" signal "L07_GND3")
		(16 "In7.Cu" signal "L08_SIG2")
		(18 "In8.Cu" signal "L09_GND4")
		(2 "B.Cu" signal "BOTTOM")
		(9 "F.Adhes" user "F.Adhesive")
		(11 "B.Adhes" user "B.Adhesive")
		(13 "F.Paste" user "Package Geometry/Pastemask Top")
		(15 "B.Paste" user "Package Geometry/Pastemask Bottom")
		(5 "F.SilkS" user "Ref Des/Silkscreen Top")
		(7 "B.SilkS" user "Ref Des/Silkscreen Bottom")
		(1 "F.Mask" user "Board Geometry/Soldermask Top")
		(3 "B.Mask" user "Board Geometry/Soldermask Bottom")
		(17 "Dwgs.User" user "User.Drawings")
		(19 "Cmts.User" user "User.Comments")
		(21 "Eco1.User" user "User.Eco1")
		(23 "Eco2.User" user "User.Eco2")
		(25 "Edge.Cuts" user "Board Geometry/Outline")
		(27 "Margin" user)
		(31 "F.CrtYd" user "Package Geometry/Place Bound Top")
		(29 "B.CrtYd" user "Package Geometry/Place Bound Bottom")
		(35 "F.Fab" user "Ref Des/Assembly Top")
		(33 "B.Fab" user "Ref Des/Assembly Bottom")
	)
	(footprint ""
		(layer "B.Cu")
		(at 28.702 -91.059 -90)
		(property "Reference" "C100"
			(at -3.175 -0.08763 270)
			(unlocked yes)
			(layer "B.SilkS")
			(effects
				(font
					(size 0.7874 0.5842)
					(thickness 0.1524)
				)
				(justify mirror)
			)
		)
		(property "Value" "VAL*"
			(at -0.0762 2.067306 270)
			(unlocked yes)
			(layer "B.Fab")
			(hide yes)
			(effects
				(font
					(size 0.7874 0.5842)
					(thickness 0.1524)
				)
				(justify mirror)
			)
		)
		(property "Tolerance" "TOL*"
			(at -0.0762 3.032506 270)
			(unlocked yes)
			(layer "Cmts.User")
			(hide yes)
			(effects
				(font
					(size 0.7874 0.5842)
					(thickness 0.1524)
				)
				(justify mirror)
			)
		)
		(property "User Part Number" "PARTNUM*"
			(at -0.1016 4.023106 270)
			(unlocked yes)
			(layer "Cmts.User")
			(hide yes)
			(effects
				(font
					(size 0.7874 0.5842)
					(thickness 0.1524)
				)
				(justify mirror)
			)
		)
		(property "Device Type" "CAPACITOR-G105-0B104-EK,0.1UF,A"
			(at -0.0508 1.127506 270)
			(unlocked yes)
			(layer "B.Fab")
			(hide yes)
			(effects
				(font
					(size 0.7874 0.5842)
					(thickness 0.1524)
				)
				(justify mirror)
			)
		)
		(duplicate_pad_numbers_are_jumpers no)
		(fp_line
			(start -1.143 0.5588)
			(end -1.143 -0.5588)
			(stroke
				(width 0.1)
				(type default)
			)
			(layer "B.SilkS")
		)
		(fp_line
			(start 1.143 0.5588)
			(end -1.143 0.5588)
			(stroke
				(width 0.1)
				(type default)
			)
			(layer "B.SilkS")
		)
		(fp_line
			(start -1.143 -0.5588)
			(end 1.143 -0.5588)
			(stroke
				(width 0.1)
				(type default)
			)
			(layer "B.SilkS")
		)
		(fp_line
			(start 1.143 -0.5588)
			(end 1.143 0.5588)
			(stroke
				(width 0.1)
				(type default)
			)
			(layer "B.SilkS")
		)
		(fp_rect
			(start 1.143 -0.5588)
			(end -1.143 0.5588)
			(stroke
				(width 0)
				(type default)
			)
			(fill no)
			(layer "B.CrtYd")
		)
		(fp_line
			(start -0.508 0.3048)
			(end -0.508 -0.3048)
			(stroke
				(width 0.1)
				(type default)
			)
			(layer "B.Fab")
		)
		(fp_line
			(start 0.508 0.3048)
			(end -0.508 0.3048)
			(stroke
				(width 0.1)
				(type default)
			)
			(layer "B.Fab")
		)
		(fp_line
			(start -0.508 -0.3048)
			(end 0.508 -0.3048)
			(stroke
				(width 0.1)
				(type default)
			)
			(layer "B.Fab")
		)
		(fp_line
			(start 0.508 -0.3048)
			(end 0.508 0.3048)
			(stroke
				(width 0.1)
				(type default)
			)
			(layer "B.Fab")
		)
		(pad "1" smd rect
			(at 0.5334 0 90)
			(size 0.7112 0.6096)
			(layers "B.Cu" "B.Mask" "B.Paste")
			(net "XP3R3V_VPLL")
		)
		(pad "2" smd rect
			(at -0.5334 0 90)
			(size 0.7112 0.6096)
			(layers "B.Cu" "B.Mask" "B.Paste")
			(net "SG")
		)
		(zone
			(layer "B.Cu")
			(hatch none 0.5)
			(connect_pads
				(clearance 0)
			)
			(min_thickness 0.25)
			(keepout
				(tracks allowed)
				(vias not_allowed)
				(pads allowed)
				(copperpour not_allowed)
				(footprints allowed)
			)
			(placement
				(enabled no)
				(sheetname "")
			)
			(fill
				(thermal_gap 0.5)
				(thermal_bridge_width 0.5)
				(island_removal_mode 0)
			)
			(polygon
				(pts
					(xy 29.0068 -90.9828) (xy 29.0068 -91.1352) (xy 28.3972 -91.1352) (xy 28.3972 -90.9828)
				)
			)
		)
	)
	(footprint ""
		(layer "B.Cu")
		(at 98.044 -64.2874 90)
		(property "Reference" "R284"
			(at 3.4036 0.21463 270)
			(unlocked yes)
			(layer "B.SilkS")
			(effects
				(font
					(size 0.7874 0.5842)
					(thickness 0.1524)
				)
				(justify mirror)
			)
		)
		(property "Value" "VAL*"
			(at -0.02032 2.13233 90)
			(unlocked yes)
			(layer "B.Fab")
			(hide yes)
			(effects
				(font
					(size 0.7874 0.5842)
					(thickness 0.1524)
				)
				(justify mirror)
			)
		)
		(property "Tolerance" "TOL*"
			(at -0.044704 3.05435 90)
			(unlocked yes)
			(layer "Cmts.User")
			(hide yes)
			(effects
				(font
					(size 0.7874 0.5842)
					(thickness 0.1524)
				)
				(justify mirror)
			)
		)
		(property "User Part Number" "PARTNUM*"
			(at -0.02032 4.024884 90)
			(unlocked yes)
			(layer "Cmts.User")
			(hide yes)
			(effects
				(font
					(size 0.7874 0.5842)
					(thickness 0.1524)
				)
				(justify mirror)
			)
		)
		(property "Device Type" "RESISTOR-G155-14701-01,4.7KOHMA"
			(at -0.008382 1.210564 90)
			(unlocked yes)
			(layer "B.Fab")
			(hide yes)
			(effects
				(font
					(size 0.7874 0.5842)
					(thickness 0.1524)
				)
				(justify mirror)
			)
		)
		(duplicate_pad_numbers_are_jumpers no)
		(fp_line
			(start 1.143 -0.5588)
			(end 1.143 0.5588)
			(stroke
				(width 0.1)
				(type default)
			)
			(layer "B.SilkS")
		)
		(fp_line
			(start -1.143 -0.5588)
			(end 1.143 -0.5588)
			(stroke
				(width 0.1)
				(type default)
			)
			(layer "B.SilkS")
		)
		(fp_line
			(start 1.143 0.5588)
			(end -1.143 0.5588)
			(stroke
				(width 0.1)
				(type default)
			)
			(layer "B.SilkS")
		)
		(fp_line
			(start -1.143 0.5588)
			(end -1.143 -0.5588)
			(stroke
				(width 0.1)
				(type default)
			)
			(layer "B.SilkS")
		)
		(fp_poly
			(pts
				(xy 1.143 0.5588) (xy -1.143 0.5588) (xy -1.143 -0.5588) (xy 1.143 -0.5588)
			)
			(stroke
				(width 0)
				(type default)
			)
			(fill no)
			(layer "B.CrtYd")
		)
		(fp_line
			(start 0.508 -0.3048)
			(end 0.508 0.3048)
			(stroke
				(width 0.1)
				(type default)
			)
			(layer "B.Fab")
		)
		(fp_line
			(start -0.508 -0.3048)
			(end 0.508 -0.3048)
			(stroke
				(width 0.1)
				(type default)
			)
			(layer "B.Fab")
		)
		(fp_line
			(start 0.508 0.3048)
			(end -0.508 0.3048)
			(stroke
				(width 0.1)
				(type default)
			)
			(layer "B.Fab")
		)
		(fp_line
			(start -0.508 0.3048)
			(end -0.508 -0.3048)
			(stroke
				(width 0.1)
				(type default)
			)
			(layer "B.Fab")
		)
		(pad "1" smd rect
			(at 0.5334 0 270)
			(size 0.7112 0.6096)
			(layers "B.Cu" "B.Mask" "B.Paste")
			(net "SG")
		)
		(pad "2" smd rect
			(at -0.5334 0 270)
			(size 0.7112 0.6096)
			(layers "B.Cu" "B.Mask" "B.Paste")
			(net "FPGA_IO_2")
		)
		(zone
			(layer "B.Cu")
			(hatch none 0.5)
			(connect_pads
				(clearance 0)
			)
			(min_thickness 0.25)
			(keepout
				(tracks not_allowed)
				(vias allowed)
				(pads allowed)
				(copperpour not_allowed)
				(footprints allowed)
			)
			(placement
				(enabled no)
				(sheetname "")
			)
			(fill
				(thermal_gap 0.5)
				(thermal_bridge_width 0.5)
				(island_removal_mode 0)
			)
			(polygon
				(pts
					(xy 98.3488 -64.3636) (xy 97.7392 -64.3636) (xy 97.7392 -64.2112) (xy 98.3488 -64.2112)
				)
			)
		)
		(zone
			(layer "B.Cu")
			(hatch none 0.5)
			(connect_pads
				(clearance 0)
			)
			(min_thickness 0.25)
			(keepout
				(tracks allowed)
				(vias not_allowed)
				(pads allowed)
				(copperpour not_allowed)
				(footprints allowed)
			)
			(placement
				(enabled no)
				(sheetname "")
			)
			(fill
				(thermal_gap 0.5)
				(thermal_bridge_width 0.5)
				(island_removal_mode 0)
			)
			(polygon
				(pts
					(xy 98.3488 -64.3636) (xy 97.7392 -64.3636) (xy 97.7392 -64.2112) (xy 98.3488 -64.2112)
				)
			)
		)
	)
)
